FILE_TYPE = CONNECTIVITY;
{Allegro Design Entry HDL 17.2-2016 S081 (4005846) 1/11/2022}
"PAGE_NUMBER" = 136;
0"NC";
1"GND\g";
2"GND\g";
3"GND\g";
4"GND\g";
5"GND\g";
6"GND\g";
7"GND\g";
8"GND\g";
9"I3C_SCM_0_R_SDA";
10"I3C_SPD_DDRAF_CPU0_BYPASS_SCL";
11"P3V3_STBY\g";
12"I3C_SCM_0_R_SCL";
13"FM_I3C_CPU0_MUX1_OE_N";
14"P3V3_STBY\g";
15"P3V3_STBY\g";
16"FM_I3C_CPU1_MUX0_OE_N";
17"FM_I3C_CPU1_MUX0_SEL";
18"I3C_SPD_DDRAF_CPU1_BYPASS_SDA";
19"P3V3_STBY\g";
20"FM_I3C_CPU1_MUX1_OE_N";
21"FM_I3C_CPU1_MUX1_SEL";
22"I3C_1_SPD_DDRGL_CPU1_SCL";
23"I3C_1_SPD_DDRGL_CPU1_SDA";
24"I3C_SCM_3_R_SCL";
25"I3C_SCM_2_R_SCL";
26"I3C_0_SPD_DDRAF_CPU0_R_SCL";
27"I3C_0_SPD_DDRAF_CPU0_R_SDA";
28"FM_I3C_CPU0_MUX0_OE_N";
29"FM_I3C_CPU0_MUX0_SEL";
30"I3C_0_SPD_DDRAF_CPU0_SCL";
31"I3C_0_SPD_DDRAF_CPU0_SDA";
32"I3C_SPD_DDRAF_CPU0_SDA";
33"I3C_SPD_DDRAF_CPU0_SCL";
34"I3C_SPD_DDRAF_CPU0_LVC1_SCL";
35"PVDD11_S3_P0\g";
36"PVDD11_S3_P1\g";
37"I3C_SPD_DDRAF_CPU1_LVC1_SCL";
38"I3C_SPD_DDRAF_CPU0_LVC1_SDA";
39"I3C_SPD_DDRAF_CPU1_BYPASS_SCL";
40"PVDD11_S3_P1\g";
41"PVDD11_S3_P1\g";
42"PVDD11_S3_P0\g";
43"PVDD11_S3_P0\g";
44"PVDD11_S3_P1\g";
45"PVDD11_S3_P0\g";
46"I3C_SPD_DDRGL_CPU1_LVC1_SCL";
47"I3C_SPD_DDRGL_CPU0_BYPASS_SCL";
48"I3C_SPD_DDRGL_CPU1_SCL";
49"I3C_SPD_DDRAF_CPU0_BYPASS_SDA";
50"I3C_SPD_DDRGL_CPU0_SDA";
51"I3C_SPD_DDRAF_CPU1_LVC1_SDA";
52"I3C_1_SPD_DDRGL_CPU1_R_SDA";
53"I3C_1_SPD_DDRGL_CPU1_R_SCL";
54"I3C_0_SPD_DDRAF_CPU1_R_SCL";
55"I3C_0_SPD_DDRAF_CPU1_R_SDA";
56"I3C_1_SPD_DDRGL_CPU0_SDA";
57"I3C_SCM_2_R_SDA";
58"I3C_SCM_3_R_SDA";
59"I3C_SCM_1_R_SDA";
60"I3C_SCM_1_R_SCL";
61"I3C_0_SPD_DDRAF_CPU1_SDA";
62"I3C_0_SPD_DDRAF_CPU1_SCL";
63"FM_I3C_CPU0_MUX1_SEL";
64"I3C_1_SPD_DDRGL_CPU0_SCL";
65"I3C_SPD_DDRGL_CPU0_BYPASS_SDA";
66"I3C_SPD_DDRGL_CPU1_LVC1_SDA";
67"I3C_SPD_DDRAF_CPU1_SCL";
68"I3C_SPD_DDRAF_CPU1_SDA";
69"I3C_SPD_DDRGL_CPU0_SCL";
70"I3C_SPD_DDRGL_CPU1_BYPASS_SCL";
71"I3C_SPD_DDRGL_CPU1_BYPASS_SDA";
72"I3C_1_SPD_DDRGL_CPU0_R_SDA";
73"I3C_1_SPD_DDRGL_CPU0_R_SCL";
74"I3C_SPD_DDRGL_CPU1_SDA";
75"I3C_SPD_DDRGL_CPU0_LVC1_SDA";
76"I3C_SPD_DDRGL_CPU0_LVC1_SCL";
%"Q_RES"
"1","(-6075,5725)","2","pure_quanta","I100";
;
LOCATION"R427"
$SEC"1"
CDS_SEC"1"
VALUE"0"
CDS_LIB"pure_quanta"
WATTAGE"1/16W"
MATERIAL"CHIP"
TOLERANCE"5%"
PART_NUMBER"CS00002JB38"
PACK_TYPE"0402LF";
"B"
$PN"2"27;
"A"
$PN"1"31;
%"Q_RES"
"1","(-6050,4375)","2","pure_quanta","I103";
;
LOCATION"R428"
$SEC"1"
CDS_SEC"1"
VALUE"0"
CDS_LIB"pure_quanta"
WATTAGE"1/16W"
MATERIAL"CHIP"
TOLERANCE"5%"
PART_NUMBER"CS00002JB38"
PACK_TYPE"0402LF";
"B"
$PN"2"73;
"A"
$PN"1"64;
%"Q_RES"
"1","(-6050,4325)","2","pure_quanta","I104";
;
LOCATION"R429"
$SEC"1"
CDS_SEC"1"
VALUE"0"
CDS_LIB"pure_quanta"
WATTAGE"1/16W"
MATERIAL"CHIP"
TOLERANCE"5%"
PART_NUMBER"CS00002JB38"
PACK_TYPE"0402LF";
"B"
$PN"2"72;
"A"
$PN"1"56;
%"Q_RES"
"1","(-6050,2800)","2","pure_quanta","I107";
;
LOCATION"R565"
$SEC"1"
CDS_SEC"1"
VALUE"0"
CDS_LIB"pure_quanta"
WATTAGE"1/16W"
MATERIAL"CHIP"
TOLERANCE"5%"
PART_NUMBER"CS00002JB38"
PACK_TYPE"0402LF";
"B"
$PN"2"55;
"A"
$PN"1"61;
%"Q_RES"
"1","(-6050,2850)","2","pure_quanta","I108";
;
LOCATION"R564"
$SEC"1"
CDS_SEC"1"
VALUE"0"
CDS_LIB"pure_quanta"
WATTAGE"1/16W"
MATERIAL"CHIP"
TOLERANCE"5%"
PART_NUMBER"CS00002JB38"
PACK_TYPE"0402LF";
"B"
$PN"2"54;
"A"
$PN"1"62;
%"Q_RES"
"1","(-5975,1400)","2","pure_quanta","I111";
;
LOCATION"R566"
$SEC"1"
CDS_SEC"1"
VALUE"0"
CDS_LIB"pure_quanta"
WATTAGE"1/16W"
MATERIAL"CHIP"
TOLERANCE"5%"
PART_NUMBER"CS00002JB38"
PACK_TYPE"0402LF";
"B"
$PN"2"53;
"A"
$PN"1"22;
%"Q_RES"
"1","(-5975,1350)","2","pure_quanta","I112";
;
LOCATION"R567"
$SEC"1"
CDS_SEC"1"
VALUE"0"
CDS_LIB"pure_quanta"
WATTAGE"1/16W"
MATERIAL"CHIP"
TOLERANCE"5%"
PART_NUMBER"CS00002JB38"
PACK_TYPE"0402LF";
"B"
$PN"2"52;
"A"
$PN"1"23;
%"Q_RES"
"1","(-6100,5325)","0","pure_quanta","I123";
;
LOCATION"R2310"
$SEC"1"
CDS_SEC"1"
MATERIAL"EMPTY"
VALUE"0"
CDS_LIB"pure_quanta"
WATTAGE"1/16W"
TOLERANCE"5%"
PART_NUMBER"CS00002JB38"
PACK_TYPE"0402LF";
"B"
$PN"2"10;
"A"
$PN"1"26;
%"Q_RES"
"1","(-6100,5275)","0","pure_quanta","I124";
;
LOCATION"R2311"
$SEC"1"
CDS_SEC"1"
MATERIAL"EMPTY"
VALUE"0"
CDS_LIB"pure_quanta"
WATTAGE"1/16W"
TOLERANCE"5%"
PART_NUMBER"CS00002JB38"
PACK_TYPE"0402LF";
"B"
$PN"2"49;
"A"
$PN"1"27;
%"Q_RES"
"1","(-3175,5325)","0","pure_quanta","I131";
;
LOCATION"R1330"
$SEC"1"
CDS_SEC"1"
VALUE"0"
MATERIAL"EMPTY"
CDS_LIB"pure_quanta"
WATTAGE"1/16W"
TOLERANCE"5%"
PART_NUMBER"CS00002JB38"
PACK_TYPE"0402LF";
"B"
$PN"2"33;
"A"
$PN"1"10;
%"Q_RES"
"1","(-3175,5275)","0","pure_quanta","I132";
;
LOCATION"R1331"
$SEC"1"
CDS_SEC"1"
MATERIAL"EMPTY"
VALUE"0"
CDS_LIB"pure_quanta"
WATTAGE"1/16W"
TOLERANCE"5%"
PART_NUMBER"CS00002JB38"
PACK_TYPE"0402LF";
"B"
$PN"2"32;
"A"
$PN"1"49;
%"Q_RES"
"1","(-3125,3875)","0","pure_quanta","I133";
;
LOCATION"R1333"
$SEC"1"
CDS_SEC"1"
MATERIAL"EMPTY"
VALUE"0"
CDS_LIB"pure_quanta"
WATTAGE"1/16W"
TOLERANCE"5%"
PART_NUMBER"CS00002JB38"
PACK_TYPE"0402LF";
"B"
$PN"2"50;
"A"
$PN"1"65;
%"Q_RES"
"1","(-3125,3925)","0","pure_quanta","I134";
;
LOCATION"R1332"
$SEC"1"
CDS_SEC"1"
VALUE"0"
MATERIAL"EMPTY"
CDS_LIB"pure_quanta"
WATTAGE"1/16W"
TOLERANCE"5%"
PART_NUMBER"CS00002JB38"
PACK_TYPE"0402LF";
"B"
$PN"2"69;
"A"
$PN"1"47;
%"Q_RES"
"1","(-6050,3925)","0","pure_quanta","I135";
;
LOCATION"R986"
$SEC"1"
CDS_SEC"1"
MATERIAL"EMPTY"
VALUE"0"
CDS_LIB"pure_quanta"
WATTAGE"1/16W"
TOLERANCE"5%"
PART_NUMBER"CS00002JB38"
PACK_TYPE"0402LF";
"B"
$PN"2"47;
"A"
$PN"1"73;
%"Q_RES"
"1","(-6050,3875)","0","pure_quanta","I136";
;
LOCATION"R987"
$SEC"1"
CDS_SEC"1"
MATERIAL"EMPTY"
VALUE"0"
CDS_LIB"pure_quanta"
WATTAGE"1/16W"
TOLERANCE"5%"
PART_NUMBER"CS00002JB38"
PACK_TYPE"0402LF";
"B"
$PN"2"65;
"A"
$PN"1"72;
%"Q_RES"
"1","(-6000,2350)","0","pure_quanta","I137";
;
LOCATION"R989"
$SEC"1"
CDS_SEC"1"
VALUE"0"
MATERIAL"EMPTY"
CDS_LIB"pure_quanta"
WATTAGE"1/16W"
TOLERANCE"5%"
PART_NUMBER"CS00002JB38"
PACK_TYPE"0402LF";
"B"
$PN"2"18;
"A"
$PN"1"55;
%"Q_RES"
"1","(-6000,2400)","0","pure_quanta","I138";
;
LOCATION"R988"
$SEC"1"
CDS_SEC"1"
VALUE"0"
MATERIAL"EMPTY"
CDS_LIB"pure_quanta"
WATTAGE"1/16W"
TOLERANCE"5%"
PART_NUMBER"CS00002JB38"
PACK_TYPE"0402LF";
"B"
$PN"2"39;
"A"
$PN"1"54;
%"Q_RES"
"1","(-3075,2400)","0","pure_quanta","I139";
;
LOCATION"R1334"
$SEC"1"
CDS_SEC"1"
MATERIAL"EMPTY"
VALUE"0"
CDS_LIB"pure_quanta"
WATTAGE"1/16W"
TOLERANCE"5%"
PART_NUMBER"CS00002JB38"
PACK_TYPE"0402LF";
"B"
$PN"2"67;
"A"
$PN"1"39;
%"Q_RES"
"1","(-3075,2350)","0","pure_quanta","I140";
;
LOCATION"R1335"
$SEC"1"
CDS_SEC"1"
MATERIAL"EMPTY"
VALUE"0"
CDS_LIB"pure_quanta"
WATTAGE"1/16W"
TOLERANCE"5%"
PART_NUMBER"CS00002JB38"
PACK_TYPE"0402LF";
"B"
$PN"2"68;
"A"
$PN"1"18;
%"Q_RES"
"1","(-5950,900)","0","pure_quanta","I141";
;
LOCATION"R991"
$SEC"1"
CDS_SEC"1"
MATERIAL"EMPTY"
VALUE"0"
CDS_LIB"pure_quanta"
WATTAGE"1/16W"
TOLERANCE"5%"
PART_NUMBER"CS00002JB38"
PACK_TYPE"0402LF";
"B"
$PN"2"71;
"A"
$PN"1"52;
%"Q_RES"
"1","(-5950,950)","0","pure_quanta","I142";
;
LOCATION"R990"
$SEC"1"
CDS_SEC"1"
MATERIAL"EMPTY"
VALUE"0"
CDS_LIB"pure_quanta"
WATTAGE"1/16W"
TOLERANCE"5%"
PART_NUMBER"CS00002JB38"
PACK_TYPE"0402LF";
"B"
$PN"2"70;
"A"
$PN"1"53;
%"Q_RES"
"1","(-3025,950)","0","pure_quanta","I143";
;
LOCATION"R1336"
$SEC"1"
CDS_SEC"1"
MATERIAL"EMPTY"
VALUE"0"
CDS_LIB"pure_quanta"
WATTAGE"1/16W"
TOLERANCE"5%"
PART_NUMBER"CS00002JB38"
PACK_TYPE"0402LF";
"B"
$PN"2"48;
"A"
$PN"1"70;
%"Q_RES"
"1","(-3025,900)","0","pure_quanta","I144";
;
LOCATION"R1337"
$SEC"1"
CDS_SEC"1"
MATERIAL"EMPTY"
VALUE"0"
CDS_LIB"pure_quanta"
WATTAGE"1/16W"
TOLERANCE"5%"
PART_NUMBER"CS00002JB38"
PACK_TYPE"0402LF";
"B"
$PN"2"74;
"A"
$PN"1"71;
%"Q_RES"
"2","(-3450,6100)","0","pure_quanta","I145";
;
LOCATION"R5006"
$SEC"1"
CDS_SEC"1"
TOLERANCE"1%"
VALUE"1K"
PACK_TYPE"0402LF"
WATTAGE"1/16W"
MATERIAL"CHIP"
CDS_LIB"pure_quanta"
PART_NUMBER"TMP_QCS21002FB24";
"A"
$PN"1"35;
"B"
$PN"2"34;
%"VCC_CORE"
"1","(-3450,6375)","0","pure_quanta_power","I146";
;
HDL_POWER"PVDD11_S3_P0"
CDS_LIB"pure_quanta_power";
"A"35;
%"Q_RES"
"2","(-3650,6100)","0","pure_quanta","I147";
;
LOCATION"R5007"
$SEC"1"
CDS_SEC"1"
VALUE"1K"
TOLERANCE"1%"
PACK_TYPE"0402LF"
WATTAGE"1/16W"
MATERIAL"CHIP"
CDS_LIB"pure_quanta"
PART_NUMBER"TMP_QCS21002FB24";
"A"
$PN"1"35;
"B"
$PN"2"38;
%"Q_RES"
"2","(-3450,4700)","0","pure_quanta","I148";
;
LOCATION"R5008"
$SEC"1"
CDS_SEC"1"
PACK_TYPE"0402LF"
VALUE"1K"
TOLERANCE"1%"
WATTAGE"1/16W"
MATERIAL"CHIP"
PART_NUMBER"TMP_QCS21002FB24"
CDS_LIB"pure_quanta";
"A"
$PN"1"45;
"B"
$PN"2"76;
%"VCC_CORE"
"1","(-3450,4975)","0","pure_quanta_power","I149";
;
HDL_POWER"PVDD11_S3_P0"
CDS_LIB"pure_quanta_power";
"A"45;
%"Q_RES"
"2","(-3650,4700)","0","pure_quanta","I150";
;
LOCATION"R5009"
$SEC"1"
CDS_SEC"1"
TOLERANCE"1%"
VALUE"1K"
PACK_TYPE"0402LF"
WATTAGE"1/16W"
MATERIAL"CHIP"
CDS_LIB"pure_quanta"
PART_NUMBER"TMP_QCS21002FB24";
"A"
$PN"1"45;
"B"
$PN"2"75;
%"Q_RES"
"2","(-3450,3175)","0","pure_quanta","I151";
;
LOCATION"R5010"
$SEC"1"
CDS_SEC"1"
VALUE"1K"
PACK_TYPE"0402LF"
TOLERANCE"1%"
WATTAGE"1/16W"
MATERIAL"CHIP"
PART_NUMBER"TMP_QCS21002FB24"
CDS_LIB"pure_quanta";
"A"
$PN"1"44;
"B"
$PN"2"37;
%"Q_RES"
"2","(-3650,3175)","0","pure_quanta","I152";
;
LOCATION"R5011"
$SEC"1"
CDS_SEC"1"
TOLERANCE"1%"
VALUE"1K"
PACK_TYPE"0402LF"
WATTAGE"1/16W"
MATERIAL"CHIP"
PART_NUMBER"TMP_QCS21002FB24"
CDS_LIB"pure_quanta";
"A"
$PN"1"44;
"B"
$PN"2"51;
%"VCC_CORE"
"1","(-3450,3450)","0","pure_quanta_power","I153";
;
HDL_POWER"PVDD11_S3_P1"
CDS_LIB"pure_quanta_power";
"A"44;
%"Q_RES"
"2","(-3650,1725)","0","pure_quanta","I154";
;
LOCATION"R5013"
$SEC"1"
CDS_SEC"1"
VALUE"1K"
TOLERANCE"1%"
WATTAGE"1/16W"
PACK_TYPE"0402LF"
MATERIAL"CHIP"
CDS_LIB"pure_quanta"
PART_NUMBER"TMP_QCS21002FB24";
"A"
$PN"1"36;
"B"
$PN"2"66;
%"VCC_CORE"
"1","(-3450,2000)","0","pure_quanta_power","I155";
;
HDL_POWER"PVDD11_S3_P1"
CDS_LIB"pure_quanta_power";
"A"36;
%"Q_RES"
"2","(-3450,1725)","0","pure_quanta","I156";
;
LOCATION"R5012"
$SEC"1"
CDS_SEC"1"
TOLERANCE"1%"
VALUE"1K"
WATTAGE"1/16W"
PACK_TYPE"0402LF"
MATERIAL"CHIP"
CDS_LIB"pure_quanta"
PART_NUMBER"TMP_QCS21002FB24";
"A"
$PN"1"36;
"B"
$PN"2"46;
%"Q_RES"
"2","(-5650,6175)","0","pure_quanta","I157";
;
LOCATION"R5015"
$SEC"1"
CDS_SEC"1"
VALUE"1K"
TOLERANCE"1%"
WATTAGE"1/16W"
PACK_TYPE"0402LF"
MATERIAL"EMPTY"
PART_NUMBER"TMP_QCS21002FB24"
CDS_LIB"pure_quanta";
"A"
$PN"1"43;
"B"
$PN"2"9;
%"VCC_CORE"
"1","(-5450,6475)","0","pure_quanta_power","I158";
;
HDL_POWER"PVDD11_S3_P0"
CDS_LIB"pure_quanta_power";
"A"43;
%"Q_RES"
"2","(-5450,6175)","0","pure_quanta","I159";
;
LOCATION"R5014"
$SEC"1"
CDS_SEC"1"
WATTAGE"1/16W"
VALUE"1K"
MATERIAL"EMPTY"
TOLERANCE"1%"
PACK_TYPE"0402LF"
PART_NUMBER"TMP_QCS21002FB24"
CDS_LIB"pure_quanta";
"A"
$PN"1"43;
"B"
$PN"2"12;
%"VCC_CORE"
"1","(-5450,4900)","0","pure_quanta_power","I160";
;
HDL_POWER"PVDD11_S3_P0"
CDS_LIB"pure_quanta_power";
"A"42;
%"Q_RES"
"2","(-5650,4700)","0","pure_quanta","I161";
;
LOCATION"R5017"
$SEC"1"
CDS_SEC"1"
WATTAGE"1/16W"
VALUE"1K"
TOLERANCE"1%"
PACK_TYPE"0402LF"
MATERIAL"EMPTY"
PART_NUMBER"TMP_QCS21002FB24"
CDS_LIB"pure_quanta";
"A"
$PN"1"42;
"B"
$PN"2"59;
%"Q_RES"
"2","(-5450,4700)","0","pure_quanta","I162";
;
LOCATION"R5016"
$SEC"1"
CDS_SEC"1"
TOLERANCE"1%"
VALUE"1K"
PACK_TYPE"0402LF"
MATERIAL"EMPTY"
WATTAGE"1/16W"
PART_NUMBER"TMP_QCS21002FB24"
CDS_LIB"pure_quanta";
"A"
$PN"1"42;
"B"
$PN"2"60;
%"Q_RES"
"2","(-5450,3175)","0","pure_quanta","I163";
;
LOCATION"R5018"
$SEC"1"
CDS_SEC"1"
PACK_TYPE"0402LF"
VALUE"1K"
TOLERANCE"1%"
MATERIAL"EMPTY"
WATTAGE"1/16W"
PART_NUMBER"TMP_QCS21002FB24"
CDS_LIB"pure_quanta";
"A"
$PN"1"41;
"B"
$PN"2"25;
%"Q_RES"
"2","(-5650,3175)","0","pure_quanta","I164";
;
LOCATION"R5019"
$SEC"1"
CDS_SEC"1"
PACK_TYPE"0402LF"
VALUE"1K"
TOLERANCE"1%"
WATTAGE"1/16W"
MATERIAL"EMPTY"
PART_NUMBER"TMP_QCS21002FB24"
CDS_LIB"pure_quanta";
"A"
$PN"1"41;
"B"
$PN"2"57;
%"VCC_CORE"
"1","(-5450,3375)","0","pure_quanta_power","I165";
;
HDL_POWER"PVDD11_S3_P1"
CDS_LIB"pure_quanta_power";
"A"41;
%"Q_RES"
"2","(-5650,1725)","0","pure_quanta","I166";
;
LOCATION"R5021"
$SEC"1"
CDS_SEC"1"
TOLERANCE"1%"
WATTAGE"1/16W"
VALUE"1K"
PACK_TYPE"0402LF"
MATERIAL"EMPTY"
CDS_LIB"pure_quanta"
PART_NUMBER"TMP_QCS21002FB24";
"A"
$PN"1"40;
"B"
$PN"2"58;
%"Q_RES"
"2","(-5450,1725)","0","pure_quanta","I167";
;
LOCATION"R5020"
$SEC"1"
CDS_SEC"1"
TOLERANCE"1%"
VALUE"1K"
PACK_TYPE"0402LF"
MATERIAL"EMPTY"
WATTAGE"1/16W"
CDS_LIB"pure_quanta"
PART_NUMBER"TMP_QCS21002FB24";
"A"
$PN"1"40;
"B"
$PN"2"24;
%"VCC_CORE"
"1","(-5450,1925)","0","pure_quanta_power","I168";
;
HDL_POWER"PVDD11_S3_P1"
CDS_LIB"pure_quanta_power";
"A"40;
%"Q_RES"
"1","(-3150,5875)","2","pure_quanta","I31";
;
LOCATION"R1297"
$SEC"1"
CDS_SEC"1"
VALUE"0"
CDS_LIB"pure_quanta"
WATTAGE"1/16W"
MATERIAL"CHIP"
TOLERANCE"5%"
PART_NUMBER"CS00002JB38"
PACK_TYPE"0402LF";
"B"
$PN"2"34;
"A"
$PN"1"33;
%"Q_RES"
"1","(-3150,5825)","2","pure_quanta","I32";
;
LOCATION"R1298"
$SEC"1"
CDS_SEC"1"
VALUE"0"
CDS_LIB"pure_quanta"
WATTAGE"1/16W"
MATERIAL"CHIP"
TOLERANCE"5%"
PART_NUMBER"CS00002JB38"
PACK_TYPE"0402LF";
"B"
$PN"2"38;
"A"
$PN"1"32;
%"Q_RES"
"1","(-3150,4475)","2","pure_quanta","I33";
;
LOCATION"R1299"
$SEC"1"
CDS_SEC"1"
VALUE"0"
CDS_LIB"pure_quanta"
WATTAGE"1/16W"
MATERIAL"CHIP"
TOLERANCE"5%"
PART_NUMBER"CS00002JB38"
PACK_TYPE"0402LF";
"B"
$PN"2"76;
"A"
$PN"1"69;
%"Q_RES"
"1","(-3150,4425)","2","pure_quanta","I34";
;
LOCATION"R1300"
$SEC"1"
CDS_SEC"1"
VALUE"0"
CDS_LIB"pure_quanta"
WATTAGE"1/16W"
MATERIAL"CHIP"
TOLERANCE"5%"
PART_NUMBER"CS00002JB38"
PACK_TYPE"0402LF";
"B"
$PN"2"75;
"A"
$PN"1"50;
%"Q_RES"
"1","(-3200,2950)","2","pure_quanta","I35";
;
LOCATION"R1293"
$SEC"1"
CDS_SEC"1"
VALUE"0"
CDS_LIB"pure_quanta"
WATTAGE"1/16W"
MATERIAL"CHIP"
TOLERANCE"5%"
PART_NUMBER"CS00002JB38"
PACK_TYPE"0402LF";
"B"
$PN"2"37;
"A"
$PN"1"67;
%"Q_RES"
"1","(-3200,2900)","2","pure_quanta","I36";
;
LOCATION"R1294"
$SEC"1"
CDS_SEC"1"
VALUE"0"
CDS_LIB"pure_quanta"
WATTAGE"1/16W"
MATERIAL"CHIP"
TOLERANCE"5%"
PART_NUMBER"CS00002JB38"
PACK_TYPE"0402LF";
"B"
$PN"2"51;
"A"
$PN"1"68;
%"Q_RES"
"1","(-3175,1500)","2","pure_quanta","I37";
;
LOCATION"R1295"
$SEC"1"
CDS_SEC"1"
VALUE"0"
CDS_LIB"pure_quanta"
WATTAGE"1/16W"
MATERIAL"CHIP"
TOLERANCE"5%"
PART_NUMBER"CS00002JB38"
PACK_TYPE"0402LF";
"B"
$PN"2"46;
"A"
$PN"1"48;
%"Q_RES"
"1","(-3175,1450)","2","pure_quanta","I38";
;
LOCATION"R1296"
$SEC"1"
CDS_SEC"1"
VALUE"0"
CDS_LIB"pure_quanta"
WATTAGE"1/16W"
MATERIAL"CHIP"
TOLERANCE"5%"
PART_NUMBER"CS00002JB38"
PACK_TYPE"0402LF";
"B"
$PN"2"66;
"A"
$PN"1"74;
%"PI3CSW12ZUAEX"
"1","(-4775,5775)","0","pure_quanta","I47";
;
LOCATION"U105"
$SEC"1"
CDS_SEC"1"
MATERIAL"IC"
PART_TYPE"SMLF"
VALUE"PI3CSW12ZUAEX"
PART_NUMBER"AL3CSW12000"
CDS_LIB"pure_quanta"
CDS_LMAN_SYM_OUTLINE"-150,200,150,-200"
NEEDS_NO_SIZE"TRUE";
"D+"
$PN"8"34;
"GND"
$PN"5"1;
"1D-"
$PN"2"31;
"VDD"
$PN"10"11;
"S"
$PN"9"29;
"OE# \B"
$PN"6"28;
"D-"
$PN"7"38;
"2D-"
$PN"4"9;
"2D+"
$PN"3"12;
"1D+"
$PN"1"30;
%"UNIVERSAL_GND"
"1","(-4325,5450)","0","pure_quanta_power","I48";
;
CDS_LIB"pure_quanta_power"
HDL_POWER"GND";
"A"1;
%"UNIVERSAL_GND"
"1","(-4275,6000)","0","pure_quanta_power","I49";
;
CDS_LIB"pure_quanta_power"
HDL_POWER"GND";
"A"2;
%"Q_CAP"
"1","(-4275,6200)","0","pure_quanta","I50";
;
LOCATION"C1336"
$SEC"1"
CDS_SEC"1"
PART_NUMBER"CH4104K1B00"
PACK_TYPE"0402"
TOLERANCE"10%"
VOLTAGE"25V"
MATERIAL"X7R"
VALUE"0.1UF"
CDS_LIB"pure_quanta";
"B"
$PN"2"2;
"A"
$PN"1"11;
%"UNIVERSAL_POWER"
"1","(-4350,6475)","2","pure_quanta_power","I51";
;
HDL_POWER"P3V3_STBY"
CDS_LIB"pure_quanta_power";
"A"11;
%"PI3CSW12ZUAEX"
"1","(-4750,4375)","0","pure_quanta","I54";
;
LOCATION"U106"
$SEC"1"
CDS_SEC"1"
VALUE"PI3CSW12ZUAEX"
PART_TYPE"SMLF"
MATERIAL"IC"
PART_NUMBER"AL3CSW12000"
CDS_LIB"pure_quanta"
CDS_LMAN_SYM_OUTLINE"-150,200,150,-200"
NEEDS_NO_SIZE"TRUE";
"D+"
$PN"8"76;
"GND"
$PN"5"4;
"1D-"
$PN"2"56;
"VDD"
$PN"10"14;
"S"
$PN"9"63;
"OE# \B"
$PN"6"13;
"D-"
$PN"7"75;
"2D-"
$PN"4"59;
"2D+"
$PN"3"60;
"1D+"
$PN"1"64;
%"UNIVERSAL_POWER"
"1","(-4325,5075)","2","pure_quanta_power","I55";
;
HDL_POWER"P3V3_STBY"
CDS_LIB"pure_quanta_power";
"A"14;
%"Q_CAP"
"1","(-4250,4800)","0","pure_quanta","I56";
;
LOCATION"C1337"
$SEC"1"
CDS_SEC"1"
MATERIAL"X7R"
TOLERANCE"10%"
VOLTAGE"25V"
PART_NUMBER"CH4104K1B00"
VALUE"0.1UF"
PACK_TYPE"0402"
CDS_LIB"pure_quanta";
"B"
$PN"2"3;
"A"
$PN"1"14;
%"UNIVERSAL_GND"
"1","(-4250,4600)","0","pure_quanta_power","I57";
;
CDS_LIB"pure_quanta_power"
HDL_POWER"GND";
"A"3;
%"UNIVERSAL_GND"
"1","(-4300,4050)","0","pure_quanta_power","I58";
;
CDS_LIB"pure_quanta_power"
HDL_POWER"GND";
"A"4;
%"UNIVERSAL_GND"
"1","(-4300,2525)","0","pure_quanta_power","I59";
;
CDS_LIB"pure_quanta_power"
HDL_POWER"GND";
"A"5;
%"UNIVERSAL_GND"
"1","(-4250,3075)","0","pure_quanta_power","I60";
;
CDS_LIB"pure_quanta_power"
HDL_POWER"GND";
"A"6;
%"Q_CAP"
"1","(-4250,3275)","0","pure_quanta","I61";
;
LOCATION"C1338"
$SEC"1"
CDS_SEC"1"
VALUE"0.1UF"
TOLERANCE"10%"
MATERIAL"X7R"
VOLTAGE"25V"
PACK_TYPE"0402"
PART_NUMBER"CH4104K1B00"
CDS_LIB"pure_quanta";
"B"
$PN"2"6;
"A"
$PN"1"15;
%"UNIVERSAL_POWER"
"1","(-4325,3550)","2","pure_quanta_power","I62";
;
HDL_POWER"P3V3_STBY"
CDS_LIB"pure_quanta_power";
"A"15;
%"PI3CSW12ZUAEX"
"1","(-4750,2850)","0","pure_quanta","I63";
;
LOCATION"U107"
$SEC"1"
CDS_SEC"1"
PART_TYPE"SMLF"
MATERIAL"IC"
VALUE"PI3CSW12ZUAEX"
PART_NUMBER"AL3CSW12000"
CDS_LIB"pure_quanta"
CDS_LMAN_SYM_OUTLINE"-150,200,150,-200"
NEEDS_NO_SIZE"TRUE";
"D+"
$PN"8"37;
"GND"
$PN"5"5;
"1D-"
$PN"2"61;
"VDD"
$PN"10"15;
"S"
$PN"9"17;
"OE# \B"
$PN"6"16;
"D-"
$PN"7"51;
"2D-"
$PN"4"57;
"2D+"
$PN"3"25;
"1D+"
$PN"1"62;
%"UNIVERSAL_GND"
"1","(-4250,1075)","0","pure_quanta_power","I64";
;
CDS_LIB"pure_quanta_power"
HDL_POWER"GND";
"A"7;
%"UNIVERSAL_GND"
"1","(-4200,1625)","0","pure_quanta_power","I65";
;
CDS_LIB"pure_quanta_power"
HDL_POWER"GND";
"A"8;
%"Q_CAP"
"1","(-4200,1825)","0","pure_quanta","I66";
;
LOCATION"C1339"
$SEC"1"
CDS_SEC"1"
VALUE"0.1UF"
PART_NUMBER"CH4104K1B00"
MATERIAL"X7R"
TOLERANCE"10%"
VOLTAGE"25V"
PACK_TYPE"0402"
CDS_LIB"pure_quanta";
"B"
$PN"2"8;
"A"
$PN"1"19;
%"UNIVERSAL_POWER"
"1","(-4275,2100)","2","pure_quanta_power","I67";
;
HDL_POWER"P3V3_STBY"
CDS_LIB"pure_quanta_power";
"A"19;
%"PI3CSW12ZUAEX"
"1","(-4700,1400)","0","pure_quanta","I68";
;
LOCATION"U108"
$SEC"1"
CDS_SEC"1"
MATERIAL"IC"
PART_TYPE"SMLF"
VALUE"PI3CSW12ZUAEX"
PART_NUMBER"AL3CSW12000"
NEEDS_NO_SIZE"TRUE"
CDS_LMAN_SYM_OUTLINE"-150,200,150,-200"
CDS_LIB"pure_quanta";
"D+"
$PN"8"46;
"GND"
$PN"5"7;
"1D-"
$PN"2"23;
"VDD"
$PN"10"19;
"S"
$PN"9"21;
"OE# \B"
$PN"6"20;
"D-"
$PN"7"66;
"2D-"
$PN"4"58;
"2D+"
$PN"3"24;
"1D+"
$PN"1"22;
%"Q_RES"
"1","(-6075,5775)","2","pure_quanta","I99";
;
LOCATION"R426"
$SEC"1"
CDS_SEC"1"
VALUE"0"
CDS_LIB"pure_quanta"
WATTAGE"1/16W"
MATERIAL"CHIP"
TOLERANCE"5%"
PART_NUMBER"CS00002JB38"
PACK_TYPE"0402LF";
"B"
$PN"2"26;
"A"
$PN"1"30;
END.
